(kicad_pcb
	(version 20260206)
	(generator "pcbnew")
	(generator_version "10.0")
	(general
		(thickness 1.6)
		(legacy_teardrops no)
	)
	(paper "A4")
	(title_block
		(title "Wiwynn_Tioga_Pass_MB.brd")
		(comment 1 "Tioga Pass / footprint 4084 of 4770 (J9T1), pads 124-243 of 291")
	)
	(layers
		(0 "F.Cu" signal "TOP")
		(4 "In1.Cu" signal "L2GND")
		(6 "In2.Cu" signal "L3")
		(8 "In3.Cu" signal "L4GND")
		(10 "In4.Cu" signal "L5")
		(12 "In5.Cu" signal "L6GND")
		(14 "In6.Cu" signal "L7VCC")
		(16 "In7.Cu" signal "L8VCC")
		(18 "In8.Cu" signal "L9GND")
		(20 "In9.Cu" signal "L10")
		(22 "In10.Cu" signal "L11GND")
		(24 "In11.Cu" signal "L12")
		(26 "In12.Cu" signal "L13GND")
		(2 "B.Cu" signal "BOTTOM")
		(9 "F.Adhes" user "F.Adhesive")
		(11 "B.Adhes" user "B.Adhesive")
		(13 "F.Paste" user "Package Geometry/Pastemask Top")
		(15 "B.Paste" user "Package Geometry/Pastemask Bottom")
		(5 "F.SilkS" user "Ref Des/Silkscreen Top")
		(7 "B.SilkS" user "Ref Des/Silkscreen Bottom")
		(1 "F.Mask" user "Board Geometry/Soldermask Top")
		(3 "B.Mask" user "Board Geometry/Soldermask Bottom")
		(17 "Dwgs.User" user "User.Drawings")
		(19 "Cmts.User" user "User.Comments")
		(21 "Eco1.User" user "User.Eco1")
		(23 "Eco2.User" user "User.Eco2")
		(25 "Edge.Cuts" user "Board Geometry/Outline")
		(27 "Margin" user)
		(31 "F.CrtYd" user "Package Geometry/Place Bound Top")
		(29 "B.CrtYd" user "Package Geometry/Place Bound Bottom")
		(35 "F.Fab" user "Ref Des/Assembly Top")
		(33 "B.Fab" user "Ref Des/Assembly Bottom")
	)
	(footprint ""
		(layer "B.Cu")
		(at 29.699458 -24.824182 90)
		(property "Reference" "J9T1"
			(at 2.200148 39.261542 0)
			(unlocked yes)
			(layer "B.SilkS")
			(effects
				(font
					(size 0.7874 0.5842)
					(thickness 0.1524)
				)
				(justify left mirror)
			)
		)
		(property "Value" ""
			(at 0 0 90)
			(layer "B.Fab")
			(effects
				(font
					(size 1.27 1.27)
				)
				(justify mirror)
			)
		)
		(duplicate_pad_numbers_are_jumpers no)
		(pad "121" smd rect
			(at 0 107.100116 270)
			(size 1.8034 0.508)
			(layers "B.Cu" "B.Mask" "B.Paste")
			(net "M_G_DQS_DP<15>")
		)
		(pad "122" smd rect
			(at 0 107.95 270)
			(size 1.8034 0.508)
			(layers "B.Cu" "B.Mask" "B.Paste")
			(net "M_G_DQS_DN<15>")
		)
		(pad "123" smd rect
			(at 0 108.799884 270)
			(size 1.8034 0.508)
			(layers "B.Cu" "B.Mask" "B.Paste")
			(net "GND")
		)
		(pad "124" smd rect
			(at 0 109.650022 270)
			(size 1.8034 0.508)
			(layers "B.Cu" "B.Mask" "B.Paste")
			(net "M_G_DQ<54>")
		)
		(pad "125" smd rect
			(at 0 110.499906 270)
			(size 1.8034 0.508)
			(layers "B.Cu" "B.Mask" "B.Paste")
			(net "GND")
		)
		(pad "126" smd rect
			(at 0 111.350044 270)
			(size 1.8034 0.508)
			(layers "B.Cu" "B.Mask" "B.Paste")
			(net "M_G_DQ<50>")
		)
		(pad "127" smd rect
			(at 0 112.199928 270)
			(size 1.8034 0.508)
			(layers "B.Cu" "B.Mask" "B.Paste")
			(net "GND")
		)
		(pad "128" smd rect
			(at 0 113.050066 270)
			(size 1.8034 0.508)
			(layers "B.Cu" "B.Mask" "B.Paste")
			(net "M_G_DQ<60>")
		)
		(pad "129" smd rect
			(at 0 113.89995 270)
			(size 1.8034 0.508)
			(layers "B.Cu" "B.Mask" "B.Paste")
			(net "GND")
		)
		(pad "130" smd rect
			(at 0 114.750088 270)
			(size 1.8034 0.508)
			(layers "B.Cu" "B.Mask" "B.Paste")
			(net "M_G_DQ<56>")
		)
		(pad "131" smd rect
			(at 0 115.599972 270)
			(size 1.8034 0.508)
			(layers "B.Cu" "B.Mask" "B.Paste")
			(net "GND")
		)
		(pad "132" smd rect
			(at 0 116.45011 270)
			(size 1.8034 0.508)
			(layers "B.Cu" "B.Mask" "B.Paste")
			(net "M_G_DQS_DP<16>")
		)
		(pad "133" smd rect
			(at 0 117.299994 270)
			(size 1.8034 0.508)
			(layers "B.Cu" "B.Mask" "B.Paste")
			(net "M_G_DQS_DN<16>")
		)
		(pad "134" smd rect
			(at 0 118.149878 270)
			(size 1.8034 0.508)
			(layers "B.Cu" "B.Mask" "B.Paste")
			(net "GND")
		)
		(pad "135" smd rect
			(at 0 119.000016 270)
			(size 1.8034 0.508)
			(layers "B.Cu" "B.Mask" "B.Paste")
			(net "M_G_DQ<62>")
		)
		(pad "136" smd rect
			(at 0 119.8499 270)
			(size 1.8034 0.508)
			(layers "B.Cu" "B.Mask" "B.Paste")
			(net "GND")
		)
		(pad "137" smd rect
			(at 0 120.700038 270)
			(size 1.8034 0.508)
			(layers "B.Cu" "B.Mask" "B.Paste")
			(net "M_G_DQ<58>")
		)
		(pad "138" smd rect
			(at 0 121.549922 270)
			(size 1.8034 0.508)
			(layers "B.Cu" "B.Mask" "B.Paste")
			(net "GND")
		)
		(pad "139" smd rect
			(at 0 122.40006 270)
			(size 1.8034 0.508)
			(layers "B.Cu" "B.Mask" "B.Paste")
			(net "PVPP_GHJ")
		)
		(pad "140" smd rect
			(at 0 123.249944 270)
			(size 1.8034 0.508)
			(layers "B.Cu" "B.Mask" "B.Paste")
			(net "GND")
		)
		(pad "141" smd rect
			(at 0 124.100082 270)
			(size 1.8034 0.508)
			(layers "B.Cu" "B.Mask" "B.Paste")
			(net "SMB_DDR_GHJ_VPP_SCL")
		)
		(pad "142" smd rect
			(at 0 124.949966 270)
			(size 1.8034 0.508)
			(layers "B.Cu" "B.Mask" "B.Paste")
			(net "PVPP_GHJ")
		)
		(pad "143" smd rect
			(at 0 125.800104 270)
			(size 1.8034 0.508)
			(layers "B.Cu" "B.Mask" "B.Paste")
			(net "PVPP_GHJ")
		)
		(pad "144" smd rect
			(at 0 126.649988 270)
			(size 1.8034 0.508)
			(layers "B.Cu" "B.Mask" "B.Paste")
			(net "TP_CH_G_DIMM0_RFU_2")
		)
		(pad "145" smd rect
			(at -4.59994 0 270)
			(size 1.8034 0.508)
			(layers "B.Cu" "B.Mask" "B.Paste")
			(net "P12V_NVDIMM_GHJ")
		)
		(pad "146" smd rect
			(at -4.59994 0.849884 270)
			(size 1.8034 0.508)
			(layers "B.Cu" "B.Mask" "B.Paste")
			(net "M_G_VREF")
		)
		(pad "147" smd rect
			(at -4.59994 1.700022 270)
			(size 1.8034 0.508)
			(layers "B.Cu" "B.Mask" "B.Paste")
			(net "GND")
		)
		(pad "148" smd rect
			(at -4.59994 2.549906 270)
			(size 1.8034 0.508)
			(layers "B.Cu" "B.Mask" "B.Paste")
			(net "M_G_DQ<5>")
		)
		(pad "149" smd rect
			(at -4.59994 3.400044 270)
			(size 1.8034 0.508)
			(layers "B.Cu" "B.Mask" "B.Paste")
			(net "GND")
		)
		(pad "150" smd rect
			(at -4.59994 4.249928 270)
			(size 1.8034 0.508)
			(layers "B.Cu" "B.Mask" "B.Paste")
			(net "M_G_DQ<1>")
		)
		(pad "151" smd rect
			(at -4.59994 5.100066 270)
			(size 1.8034 0.508)
			(layers "B.Cu" "B.Mask" "B.Paste")
			(net "GND")
		)
		(pad "152" smd rect
			(at -4.59994 5.94995 270)
			(size 1.8034 0.508)
			(layers "B.Cu" "B.Mask" "B.Paste")
			(net "M_G_DQS_DN<0>")
		)
		(pad "153" smd rect
			(at -4.59994 6.800088 270)
			(size 1.8034 0.508)
			(layers "B.Cu" "B.Mask" "B.Paste")
			(net "M_G_DQS_DP<0>")
		)
		(pad "154" smd rect
			(at -4.59994 7.649972 270)
			(size 1.8034 0.508)
			(layers "B.Cu" "B.Mask" "B.Paste")
			(net "GND")
		)
		(pad "155" smd rect
			(at -4.59994 8.50011 270)
			(size 1.8034 0.508)
			(layers "B.Cu" "B.Mask" "B.Paste")
			(net "M_G_DQ<7>")
		)
		(pad "156" smd rect
			(at -4.59994 9.349994 270)
			(size 1.8034 0.508)
			(layers "B.Cu" "B.Mask" "B.Paste")
			(net "GND")
		)
		(pad "157" smd rect
			(at -4.59994 10.199878 270)
			(size 1.8034 0.508)
			(layers "B.Cu" "B.Mask" "B.Paste")
			(net "M_G_DQ<3>")
		)
		(pad "158" smd rect
			(at -4.59994 11.050016 270)
			(size 1.8034 0.508)
			(layers "B.Cu" "B.Mask" "B.Paste")
			(net "GND")
		)
		(pad "159" smd rect
			(at -4.59994 11.8999 270)
			(size 1.8034 0.508)
			(layers "B.Cu" "B.Mask" "B.Paste")
			(net "M_G_DQ<13>")
		)
		(pad "160" smd rect
			(at -4.59994 12.750038 270)
			(size 1.8034 0.508)
			(layers "B.Cu" "B.Mask" "B.Paste")
			(net "GND")
		)
		(pad "161" smd rect
			(at -4.59994 13.599922 270)
			(size 1.8034 0.508)
			(layers "B.Cu" "B.Mask" "B.Paste")
			(net "M_G_DQ<9>")
		)
		(pad "162" smd rect
			(at -4.59994 14.45006 270)
			(size 1.8034 0.508)
			(layers "B.Cu" "B.Mask" "B.Paste")
			(net "GND")
		)
		(pad "163" smd rect
			(at -4.59994 15.299944 270)
			(size 1.8034 0.508)
			(layers "B.Cu" "B.Mask" "B.Paste")
			(net "M_G_DQS_DN<1>")
		)
		(pad "164" smd rect
			(at -4.59994 16.150082 270)
			(size 1.8034 0.508)
			(layers "B.Cu" "B.Mask" "B.Paste")
			(net "M_G_DQS_DP<1>")
		)
		(pad "165" smd rect
			(at -4.59994 16.999966 270)
			(size 1.8034 0.508)
			(layers "B.Cu" "B.Mask" "B.Paste")
			(net "GND")
		)
		(pad "166" smd rect
			(at -4.59994 17.850104 270)
			(size 1.8034 0.508)
			(layers "B.Cu" "B.Mask" "B.Paste")
			(net "M_G_DQ<15>")
		)
		(pad "167" smd rect
			(at -4.59994 18.699988 270)
			(size 1.8034 0.508)
			(layers "B.Cu" "B.Mask" "B.Paste")
			(net "GND")
		)
		(pad "168" smd rect
			(at -4.59994 19.550126 270)
			(size 1.8034 0.508)
			(layers "B.Cu" "B.Mask" "B.Paste")
			(net "M_G_DQ<11>")
		)
		(pad "169" smd rect
			(at -4.59994 20.40001 270)
			(size 1.8034 0.508)
			(layers "B.Cu" "B.Mask" "B.Paste")
			(net "GND")
		)
		(pad "170" smd rect
			(at -4.59994 21.249894 270)
			(size 1.8034 0.508)
			(layers "B.Cu" "B.Mask" "B.Paste")
			(net "M_G_DQ<21>")
		)
		(pad "171" smd rect
			(at -4.59994 22.100032 270)
			(size 1.8034 0.508)
			(layers "B.Cu" "B.Mask" "B.Paste")
			(net "GND")
		)
		(pad "172" smd rect
			(at -4.59994 22.949916 270)
			(size 1.8034 0.508)
			(layers "B.Cu" "B.Mask" "B.Paste")
			(net "M_G_DQ<17>")
		)
		(pad "173" smd rect
			(at -4.59994 23.800054 270)
			(size 1.8034 0.508)
			(layers "B.Cu" "B.Mask" "B.Paste")
			(net "GND")
		)
		(pad "174" smd rect
			(at -4.59994 24.649938 270)
			(size 1.8034 0.508)
			(layers "B.Cu" "B.Mask" "B.Paste")
			(net "M_G_DQS_DN<2>")
		)
		(pad "175" smd rect
			(at -4.59994 25.500076 270)
			(size 1.8034 0.508)
			(layers "B.Cu" "B.Mask" "B.Paste")
			(net "M_G_DQS_DP<2>")
		)
		(pad "176" smd rect
			(at -4.59994 26.34996 270)
			(size 1.8034 0.508)
			(layers "B.Cu" "B.Mask" "B.Paste")
			(net "GND")
		)
		(pad "177" smd rect
			(at -4.59994 27.200098 270)
			(size 1.8034 0.508)
			(layers "B.Cu" "B.Mask" "B.Paste")
			(net "M_G_DQ<23>")
		)
		(pad "178" smd rect
			(at -4.59994 28.049982 270)
			(size 1.8034 0.508)
			(layers "B.Cu" "B.Mask" "B.Paste")
			(net "GND")
		)
		(pad "179" smd rect
			(at -4.59994 28.90012 270)
			(size 1.8034 0.508)
			(layers "B.Cu" "B.Mask" "B.Paste")
			(net "M_G_DQ<19>")
		)
		(pad "180" smd rect
			(at -4.59994 29.750004 270)
			(size 1.8034 0.508)
			(layers "B.Cu" "B.Mask" "B.Paste")
			(net "GND")
		)
		(pad "181" smd rect
			(at -4.59994 30.599888 270)
			(size 1.8034 0.508)
			(layers "B.Cu" "B.Mask" "B.Paste")
			(net "M_G_DQ<29>")
		)
		(pad "182" smd rect
			(at -4.59994 31.450026 270)
			(size 1.8034 0.508)
			(layers "B.Cu" "B.Mask" "B.Paste")
			(net "GND")
		)
		(pad "183" smd rect
			(at -4.59994 32.29991 270)
			(size 1.8034 0.508)
			(layers "B.Cu" "B.Mask" "B.Paste")
			(net "M_G_DQ<25>")
		)
		(pad "184" smd rect
			(at -4.59994 33.150048 270)
			(size 1.8034 0.508)
			(layers "B.Cu" "B.Mask" "B.Paste")
			(net "GND")
		)
		(pad "185" smd rect
			(at -4.59994 33.999932 270)
			(size 1.8034 0.508)
			(layers "B.Cu" "B.Mask" "B.Paste")
			(net "M_G_DQS_DN<3>")
		)
		(pad "186" smd rect
			(at -4.59994 34.85007 270)
			(size 1.8034 0.508)
			(layers "B.Cu" "B.Mask" "B.Paste")
			(net "M_G_DQS_DP<3>")
		)
		(pad "187" smd rect
			(at -4.59994 35.699954 270)
			(size 1.8034 0.508)
			(layers "B.Cu" "B.Mask" "B.Paste")
			(net "GND")
		)
		(pad "188" smd rect
			(at -4.59994 36.550092 270)
			(size 1.8034 0.508)
			(layers "B.Cu" "B.Mask" "B.Paste")
			(net "M_G_DQ<31>")
		)
		(pad "189" smd rect
			(at -4.59994 37.399976 270)
			(size 1.8034 0.508)
			(layers "B.Cu" "B.Mask" "B.Paste")
			(net "GND")
		)
		(pad "190" smd rect
			(at -4.59994 38.250114 270)
			(size 1.8034 0.508)
			(layers "B.Cu" "B.Mask" "B.Paste")
			(net "M_G_DQ<27>")
		)
		(pad "191" smd rect
			(at -4.59994 39.099998 270)
			(size 1.8034 0.508)
			(layers "B.Cu" "B.Mask" "B.Paste")
			(net "GND")
		)
		(pad "192" smd rect
			(at -4.59994 39.949882 270)
			(size 1.8034 0.508)
			(layers "B.Cu" "B.Mask" "B.Paste")
			(net "M_G_ECC<5>")
		)
		(pad "193" smd rect
			(at -4.59994 40.80002 270)
			(size 1.8034 0.508)
			(layers "B.Cu" "B.Mask" "B.Paste")
			(net "GND")
		)
		(pad "194" smd rect
			(at -4.59994 41.649904 270)
			(size 1.8034 0.508)
			(layers "B.Cu" "B.Mask" "B.Paste")
			(net "M_G_ECC<1>")
		)
		(pad "195" smd rect
			(at -4.59994 42.500042 270)
			(size 1.8034 0.508)
			(layers "B.Cu" "B.Mask" "B.Paste")
			(net "GND")
		)
		(pad "196" smd rect
			(at -4.59994 43.349926 270)
			(size 1.8034 0.508)
			(layers "B.Cu" "B.Mask" "B.Paste")
			(net "M_G_DQS_DN<8>")
		)
		(pad "197" smd rect
			(at -4.59994 44.200064 270)
			(size 1.8034 0.508)
			(layers "B.Cu" "B.Mask" "B.Paste")
			(net "M_G_DQS_DP<8>")
		)
		(pad "198" smd rect
			(at -4.59994 45.049948 270)
			(size 1.8034 0.508)
			(layers "B.Cu" "B.Mask" "B.Paste")
			(net "GND")
		)
		(pad "199" smd rect
			(at -4.59994 45.900086 270)
			(size 1.8034 0.508)
			(layers "B.Cu" "B.Mask" "B.Paste")
			(net "M_G_ECC<7>")
		)
		(pad "200" smd rect
			(at -4.59994 46.74997 270)
			(size 1.8034 0.508)
			(layers "B.Cu" "B.Mask" "B.Paste")
			(net "GND")
		)
		(pad "201" smd rect
			(at -4.59994 47.600108 270)
			(size 1.8034 0.508)
			(layers "B.Cu" "B.Mask" "B.Paste")
			(net "M_G_ECC<3>")
		)
		(pad "202" smd rect
			(at -4.59994 48.449992 270)
			(size 1.8034 0.508)
			(layers "B.Cu" "B.Mask" "B.Paste")
			(net "GND")
		)
		(pad "203" smd rect
			(at -4.59994 49.299876 270)
			(size 1.8034 0.508)
			(layers "B.Cu" "B.Mask" "B.Paste")
			(net "M_G_CKE<3>")
		)
		(pad "204" smd rect
			(at -4.59994 50.150014 270)
			(size 1.8034 0.508)
			(layers "B.Cu" "B.Mask" "B.Paste")
			(net "PVDDQ_GHJ")
		)
		(pad "205" smd rect
			(at -4.59994 50.999898 270)
			(size 1.8034 0.508)
			(layers "B.Cu" "B.Mask" "B.Paste")
			(net "TP_CH_G_DIMM0_RFU_0")
		)
		(pad "206" smd rect
			(at -4.59994 51.850036 270)
			(size 1.8034 0.508)
			(layers "B.Cu" "B.Mask" "B.Paste")
			(net "PVDDQ_GHJ")
		)
		(pad "207" smd rect
			(at -4.59994 52.69992 270)
			(size 1.8034 0.508)
			(layers "B.Cu" "B.Mask" "B.Paste")
			(net "M_G_BG<1>")
		)
		(pad "208" smd rect
			(at -4.59994 53.550058 270)
			(size 1.8034 0.508)
			(layers "B.Cu" "B.Mask" "B.Paste")
			(net "M_G_ALERT_N")
		)
		(pad "209" smd rect
			(at -4.59994 54.399942 270)
			(size 1.8034 0.508)
			(layers "B.Cu" "B.Mask" "B.Paste")
			(net "PVDDQ_GHJ")
		)
		(pad "210" smd rect
			(at -4.59994 55.25008 270)
			(size 1.8034 0.508)
			(layers "B.Cu" "B.Mask" "B.Paste")
			(net "M_G_MA<11>")
		)
		(pad "211" smd rect
			(at -4.59994 56.099964 270)
			(size 1.8034 0.508)
			(layers "B.Cu" "B.Mask" "B.Paste")
			(net "M_G_MA<7>")
		)
		(pad "212" smd rect
			(at -4.59994 56.950102 270)
			(size 1.8034 0.508)
			(layers "B.Cu" "B.Mask" "B.Paste")
			(net "PVDDQ_GHJ")
		)
		(pad "213" smd rect
			(at -4.59994 57.799986 270)
			(size 1.8034 0.508)
			(layers "B.Cu" "B.Mask" "B.Paste")
			(net "M_G_MA<5>")
		)
		(pad "214" smd rect
			(at -4.59994 58.650124 270)
			(size 1.8034 0.508)
			(layers "B.Cu" "B.Mask" "B.Paste")
			(net "M_G_MA<4>")
		)
		(pad "215" smd rect
			(at -4.59994 59.500008 270)
			(size 1.8034 0.508)
			(layers "B.Cu" "B.Mask" "B.Paste")
			(net "PVDDQ_GHJ")
		)
		(pad "216" smd rect
			(at -4.59994 60.349892 270)
			(size 1.8034 0.508)
			(layers "B.Cu" "B.Mask" "B.Paste")
			(net "M_G_MA<2>")
		)
		(pad "217" smd rect
			(at -4.59994 61.20003 270)
			(size 1.8034 0.508)
			(layers "B.Cu" "B.Mask" "B.Paste")
			(net "PVDDQ_GHJ")
		)
		(pad "218" smd rect
			(at -4.59994 62.049914 270)
			(size 1.8034 0.508)
			(layers "B.Cu" "B.Mask" "B.Paste")
			(net "M_G_CLK_DP<3>")
		)
		(pad "219" smd rect
			(at -4.59994 62.900052 270)
			(size 1.8034 0.508)
			(layers "B.Cu" "B.Mask" "B.Paste")
			(net "M_G_CLK_DN<3>")
		)
		(pad "220" smd rect
			(at -4.59994 63.749936 270)
			(size 1.8034 0.508)
			(layers "B.Cu" "B.Mask" "B.Paste")
			(net "PVDDQ_GHJ")
		)
		(pad "221" smd rect
			(at -4.59994 64.600074 270)
			(size 1.8034 0.508)
			(layers "B.Cu" "B.Mask" "B.Paste")
			(net "PVTT_GHJ")
		)
		(pad "222" smd rect
			(at -4.59994 70.550024 270)
			(size 1.8034 0.508)
			(layers "B.Cu" "B.Mask" "B.Paste")
			(net "M_G_PAR")
		)
		(pad "223" smd rect
			(at -4.59994 71.399908 270)
			(size 1.8034 0.508)
			(layers "B.Cu" "B.Mask" "B.Paste")
			(net "PVDDQ_GHJ")
		)
		(pad "224" smd rect
			(at -4.59994 72.250046 270)
			(size 1.8034 0.508)
			(layers "B.Cu" "B.Mask" "B.Paste")
			(net "M_G_BA<1>")
		)
		(pad "225" smd rect
			(at -4.59994 73.09993 270)
			(size 1.8034 0.508)
			(layers "B.Cu" "B.Mask" "B.Paste")
			(net "M_G_MA<10>")
		)
		(pad "226" smd rect
			(at -4.59994 73.950068 270)
			(size 1.8034 0.508)
			(layers "B.Cu" "B.Mask" "B.Paste")
			(net "PVDDQ_GHJ")
		)
		(pad "227" smd rect
			(at -4.59994 74.799952 270)
			(size 1.8034 0.508)
			(layers "B.Cu" "B.Mask" "B.Paste")
			(net "TP_CH_G_DIMM0_RFU_1")
		)
		(pad "228" smd rect
			(at -4.59994 75.65009 270)
			(size 1.8034 0.508)
			(layers "B.Cu" "B.Mask" "B.Paste")
			(net "M_G_MA<14>")
		)
		(pad "229" smd rect
			(at -4.59994 76.499974 270)
			(size 1.8034 0.508)
			(layers "B.Cu" "B.Mask" "B.Paste")
			(net "PVDDQ_GHJ")
		)
		(pad "230" smd rect
			(at -4.59994 77.350112 270)
			(size 1.8034 0.508)
			(layers "B.Cu" "B.Mask" "B.Paste")
			(net "FM_ADR_COMPLETE_GHJ_N")
		)
		(pad "231" smd rect
			(at -4.59994 78.199996 270)
			(size 1.8034 0.508)
			(layers "B.Cu" "B.Mask" "B.Paste")
			(net "PVDDQ_GHJ")
		)
		(pad "232" smd rect
			(at -4.59994 79.04988 270)
			(size 1.8034 0.508)
			(layers "B.Cu" "B.Mask" "B.Paste")
			(net "M_G_MA<13>")
		)
		(pad "233" smd rect
			(at -4.59994 79.900018 270)
			(size 1.8034 0.508)
			(layers "B.Cu" "B.Mask" "B.Paste")
			(net "PVDDQ_GHJ")
		)
		(pad "234" smd rect
			(at -4.59994 80.749902 270)
			(size 1.8034 0.508)
			(layers "B.Cu" "B.Mask" "B.Paste")
			(net "M_G_MA<17>")
		)
		(pad "235" smd rect
			(at -4.59994 81.60004 270)
			(size 1.8034 0.508)
			(layers "B.Cu" "B.Mask" "B.Paste")
			(net "M_G_C<2>")
		)
		(pad "236" smd rect
			(at -4.59994 82.449924 270)
			(size 1.8034 0.508)
			(layers "B.Cu" "B.Mask" "B.Paste")
			(net "PVDDQ_GHJ")
		)
		(pad "237" smd rect
			(at -4.59994 83.300062 270)
			(size 1.8034 0.508)
			(layers "B.Cu" "B.Mask" "B.Paste")
			(net "M_G_CS_N<7>")
		)
		(pad "238" smd rect
			(at -4.59994 84.149946 270)
			(size 1.8034 0.508)
			(layers "B.Cu" "B.Mask" "B.Paste")
			(net "GND")
		)
		(pad "239" smd rect
			(at -4.59994 85.000084 270)
			(size 1.8034 0.508)
			(layers "B.Cu" "B.Mask" "B.Paste")
			(net "GND")
		)
		(pad "240" smd rect
			(at -4.59994 85.849968 270)
			(size 1.8034 0.508)
			(layers "B.Cu" "B.Mask" "B.Paste")
			(net "M_G_DQ<37>")
		)
	)
)
